(kicad_pcb
	(version 20260206)
	(generator "pcbnew")
	(generator_version "10.0")
	(general
		(thickness 1.6)
		(legacy_teardrops no)
	)
	(paper "A4")
	(title_block
		(title "04192023_DAF0TMB3IC0_F0TG_MB_C_brd_V02_OCP.brd")
		(comment 1 "Grand Teton / footprints 3255-3261 of 8354")
	)
	(layers
		(0 "F.Cu" signal "TOP")
		(4 "In1.Cu" signal "GND")
		(6 "In2.Cu" signal "IN1")
		(8 "In3.Cu" signal "GND1")
		(10 "In4.Cu" signal "IN2")
		(12 "In5.Cu" signal "GND2")
		(14 "In6.Cu" signal "IN3")
		(16 "In7.Cu" signal "GND3")
		(18 "In8.Cu" signal "VCC")
		(20 "In9.Cu" signal "VCC1")
		(22 "In10.Cu" signal "GND4")
		(24 "In11.Cu" signal "IN4")
		(26 "In12.Cu" signal "GND5")
		(28 "In13.Cu" signal "IN5")
		(30 "In14.Cu" signal "GND6")
		(32 "In15.Cu" signal "IN6")
		(34 "In16.Cu" signal "GND7")
		(2 "B.Cu" signal "BOTTOM")
		(9 "F.Adhes" user "F.Adhesive")
		(11 "B.Adhes" user "B.Adhesive")
		(13 "F.Paste" user "Package Geometry/Pastemask Top")
		(15 "B.Paste" user "Package Geometry/Pastemask Bottom")
		(5 "F.SilkS" user "Ref Des/Silkscreen Top")
		(7 "B.SilkS" user "Ref Des/Silkscreen Bottom")
		(1 "F.Mask" user "Board Geometry/Soldermask Top")
		(3 "B.Mask" user "Board Geometry/Soldermask Bottom")
		(17 "Dwgs.User" user "User.Drawings")
		(19 "Cmts.User" user "User.Comments")
		(21 "Eco1.User" user "User.Eco1")
		(23 "Eco2.User" user "User.Eco2")
		(25 "Edge.Cuts" user "Board Geometry/Outline")
		(27 "Margin" user)
		(31 "F.CrtYd" user "Package Geometry/Place Bound Top")
		(29 "B.CrtYd" user "Package Geometry/Place Bound Bottom")
		(35 "F.Fab" user "Ref Des/Assembly Top")
		(33 "B.Fab" user "Ref Des/Assembly Bottom")
	)
	(footprint ""
		(layer "F.Cu")
		(at 247.499378 -315.82868 90)
		(property "Reference" "PC6805"
			(at -1.75768 5.257292 90)
			(unlocked yes)
			(layer "F.SilkS")
			(effects
				(font
					(size 0.7874 0.5842)
					(thickness 0.1524)
				)
				(justify left)
			)
		)
		(property "Value" ""
			(at 0 0 90)
			(layer "F.Fab")
			(effects
				(font
					(size 1.27 1.27)
				)
			)
		)
		(duplicate_pad_numbers_are_jumpers no)
		(fp_line
			(start 2.750058 -2.750058)
			(end -1.988058 -2.750058)
			(stroke
				(width 0.1524)
				(type default)
			)
			(layer "F.SilkS")
		)
		(fp_line
			(start -1.988058 -2.750058)
			(end -2.750058 -1.988058)
			(stroke
				(width 0.1524)
				(type default)
			)
			(layer "F.SilkS")
		)
		(fp_line
			(start -2.750058 -1.988058)
			(end -2.750058 -0.9398)
			(stroke
				(width 0.1524)
				(type default)
			)
			(layer "F.SilkS")
		)
		(fp_line
			(start 2.750058 -0.9398)
			(end 2.750058 -2.750058)
			(stroke
				(width 0.1524)
				(type default)
			)
			(layer "F.SilkS")
		)
		(fp_line
			(start -2.750058 0.9398)
			(end -2.750058 1.988058)
			(stroke
				(width 0.1524)
				(type default)
			)
			(layer "F.SilkS")
		)
		(fp_line
			(start -2.750058 1.988058)
			(end -1.988058 2.750058)
			(stroke
				(width 0.1524)
				(type default)
			)
			(layer "F.SilkS")
		)
		(fp_line
			(start 2.750058 2.750058)
			(end 2.750058 0.9398)
			(stroke
				(width 0.1524)
				(type default)
			)
			(layer "F.SilkS")
		)
		(fp_line
			(start -1.988058 2.750058)
			(end 2.750058 2.750058)
			(stroke
				(width 0.1524)
				(type default)
			)
			(layer "F.SilkS")
		)
		(fp_line
			(start 2.750058 -2.750058)
			(end -2.750058 -2.750058)
			(stroke
				(width 0.1)
				(type default)
			)
			(layer "F.Fab")
		)
		(fp_line
			(start -2.750058 -2.750058)
			(end -2.750058 2.750058)
			(stroke
				(width 0.1)
				(type default)
			)
			(layer "F.Fab")
		)
		(fp_line
			(start 2.750058 2.750058)
			(end 2.750058 -2.750058)
			(stroke
				(width 0.1)
				(type default)
			)
			(layer "F.Fab")
		)
		(fp_line
			(start -2.750058 2.750058)
			(end 2.750058 2.750058)
			(stroke
				(width 0.1)
				(type default)
			)
			(layer "F.Fab")
		)
		(pad "1" smd rect
			(at -2.199894 0 180)
			(size 1.6002 3.0226)
			(layers "F.Cu" "F.Mask" "F.Paste")
			(net "P1V8_CPU0_RT_1D")
		)
		(pad "2" smd rect
			(at 2.199894 0 180)
			(size 1.6002 3.0226)
			(layers "F.Cu" "F.Mask" "F.Paste")
			(net "GND")
		)
	)
	(footprint ""
		(layer "F.Cu")
		(at 255.780794 -138.048746 90)
		(property "Reference" "R129"
			(at 0 0 90)
			(layer "F.SilkS")
			(hide yes)
			(effects
				(font
					(size 1.27 1.27)
				)
			)
		)
		(property "Value" ""
			(at 0 0 90)
			(layer "F.Fab")
			(effects
				(font
					(size 1.27 1.27)
				)
			)
		)
		(duplicate_pad_numbers_are_jumpers no)
		(fp_line
			(start 0.7874 -0.4064)
			(end 0.7874 0.4064)
			(stroke
				(width 0.1524)
				(type default)
			)
			(layer "F.SilkS")
		)
		(fp_line
			(start -0.7874 -0.4064)
			(end 0.7874 -0.4064)
			(stroke
				(width 0.1524)
				(type default)
			)
			(layer "F.SilkS")
		)
		(fp_line
			(start 0.7874 0.4064)
			(end -0.7874 0.4064)
			(stroke
				(width 0.1524)
				(type default)
			)
			(layer "F.SilkS")
		)
		(fp_line
			(start -0.7874 0.4064)
			(end -0.7874 -0.4064)
			(stroke
				(width 0.1524)
				(type default)
			)
			(layer "F.SilkS")
		)
		(fp_line
			(start -0.12065 -0.305054)
			(end -0.12065 -0.2794)
			(stroke
				(width 0.1)
				(type default)
			)
			(layer "F.Fab")
		)
		(fp_line
			(start -0.67945 -0.305054)
			(end -0.12065 -0.305054)
			(stroke
				(width 0.1)
				(type default)
			)
			(layer "F.Fab")
		)
		(fp_line
			(start 0.67945 -0.3048)
			(end 0.67945 0.3048)
			(stroke
				(width 0.1)
				(type default)
			)
			(layer "F.Fab")
		)
		(fp_line
			(start 0.12065 -0.3048)
			(end 0.67945 -0.3048)
			(stroke
				(width 0.1)
				(type default)
			)
			(layer "F.Fab")
		)
		(fp_line
			(start 0.12065 -0.2794)
			(end 0.12065 -0.3048)
			(stroke
				(width 0.1)
				(type default)
			)
			(layer "F.Fab")
		)
		(fp_line
			(start -0.12065 -0.2794)
			(end 0.12065 -0.2794)
			(stroke
				(width 0.1)
				(type default)
			)
			(layer "F.Fab")
		)
		(fp_line
			(start 0.120396 0.2794)
			(end -0.12065 0.2794)
			(stroke
				(width 0.1)
				(type default)
			)
			(layer "F.Fab")
		)
		(fp_line
			(start -0.12065 0.2794)
			(end -0.12065 0.3048)
			(stroke
				(width 0.1)
				(type default)
			)
			(layer "F.Fab")
		)
		(fp_line
			(start 0.67945 0.3048)
			(end 0.120396 0.3048)
			(stroke
				(width 0.1)
				(type default)
			)
			(layer "F.Fab")
		)
		(fp_line
			(start 0.120396 0.3048)
			(end 0.120396 0.2794)
			(stroke
				(width 0.1)
				(type default)
			)
			(layer "F.Fab")
		)
		(fp_line
			(start -0.12065 0.3048)
			(end -0.67945 0.3048)
			(stroke
				(width 0.1)
				(type default)
			)
			(layer "F.Fab")
		)
		(fp_line
			(start -0.67945 0.3048)
			(end -0.67945 -0.305054)
			(stroke
				(width 0.1)
				(type default)
			)
			(layer "F.Fab")
		)
		(pad "1" smd circle
			(at -0.40005 0 90)
			(size 0 0)
			(layers "F.Cu" "F.Mask" "F.Paste")
			(net "P3V3_AUX")
		)
		(pad "2" smd circle
			(at 0.40005 0 90)
			(size 0 0)
			(layers "F.Cu" "F.Mask" "F.Paste")
			(net "SPI_CPU0_LVC3_SCM_D3")
		)
	)
	(footprint ""
		(layer "F.Cu")
		(at 122.916696 -375.49963 -90)
		(property "Reference" "C1532"
			(at 0 0 270)
			(layer "F.SilkS")
			(hide yes)
			(effects
				(font
					(size 1.27 1.27)
				)
			)
		)
		(property "Value" ""
			(at 0 0 270)
			(layer "F.Fab")
			(effects
				(font
					(size 1.27 1.27)
				)
			)
		)
		(duplicate_pad_numbers_are_jumpers no)
		(fp_line
			(start -0.299974 0.150114)
			(end -0.299974 -0.150114)
			(stroke
				(width 0.1)
				(type default)
			)
			(layer "F.Fab")
		)
		(fp_line
			(start 0.299974 0.150114)
			(end -0.299974 0.150114)
			(stroke
				(width 0.1)
				(type default)
			)
			(layer "F.Fab")
		)
		(fp_line
			(start -0.299974 -0.150114)
			(end 0.299974 -0.150114)
			(stroke
				(width 0.1)
				(type default)
			)
			(layer "F.Fab")
		)
		(fp_line
			(start 0.299974 -0.150114)
			(end 0.299974 0.150114)
			(stroke
				(width 0.1)
				(type default)
			)
			(layer "F.Fab")
		)
		(pad "1" smd rect
			(at -0.2667 0 270)
			(size 0.3048 0.381)
			(layers "F.Cu" "F.Mask" "F.Paste")
			(net "P5E_CPU1_P3_TX_C_DN<7>")
		)
		(pad "2" smd rect
			(at 0.2667 0 270)
			(size 0.3048 0.381)
			(layers "F.Cu" "F.Mask" "F.Paste")
			(net "P5E_CPU1_P3_TX_DN<7>")
		)
	)
	(footprint ""
		(layer "F.Cu")
		(at 224.21215 -48.78197 180)
		(property "Reference" "R2426"
			(at 0 0 180)
			(layer "F.SilkS")
			(hide yes)
			(effects
				(font
					(size 1.27 1.27)
				)
			)
		)
		(property "Value" ""
			(at 0 0 180)
			(layer "F.Fab")
			(effects
				(font
					(size 1.27 1.27)
				)
			)
		)
		(duplicate_pad_numbers_are_jumpers no)
		(fp_line
			(start 0.7874 0.4064)
			(end -0.7874 0.4064)
			(stroke
				(width 0.1524)
				(type default)
			)
			(layer "F.SilkS")
		)
		(fp_line
			(start 0.7874 -0.4064)
			(end 0.7874 0.4064)
			(stroke
				(width 0.1524)
				(type default)
			)
			(layer "F.SilkS")
		)
		(fp_line
			(start -0.7874 0.4064)
			(end -0.7874 -0.4064)
			(stroke
				(width 0.1524)
				(type default)
			)
			(layer "F.SilkS")
		)
		(fp_line
			(start -0.7874 -0.4064)
			(end 0.7874 -0.4064)
			(stroke
				(width 0.1524)
				(type default)
			)
			(layer "F.SilkS")
		)
		(fp_line
			(start 0.67945 0.3048)
			(end 0.120396 0.3048)
			(stroke
				(width 0.1)
				(type default)
			)
			(layer "F.Fab")
		)
		(fp_line
			(start 0.67945 -0.3048)
			(end 0.67945 0.3048)
			(stroke
				(width 0.1)
				(type default)
			)
			(layer "F.Fab")
		)
		(fp_line
			(start 0.12065 -0.2794)
			(end 0.12065 -0.3048)
			(stroke
				(width 0.1)
				(type default)
			)
			(layer "F.Fab")
		)
		(fp_line
			(start 0.12065 -0.3048)
			(end 0.67945 -0.3048)
			(stroke
				(width 0.1)
				(type default)
			)
			(layer "F.Fab")
		)
		(fp_line
			(start 0.120396 0.3048)
			(end 0.120396 0.2794)
			(stroke
				(width 0.1)
				(type default)
			)
			(layer "F.Fab")
		)
		(fp_line
			(start 0.120396 0.2794)
			(end -0.12065 0.2794)
			(stroke
				(width 0.1)
				(type default)
			)
			(layer "F.Fab")
		)
		(fp_line
			(start -0.12065 0.3048)
			(end -0.67945 0.3048)
			(stroke
				(width 0.1)
				(type default)
			)
			(layer "F.Fab")
		)
		(fp_line
			(start -0.12065 0.2794)
			(end -0.12065 0.3048)
			(stroke
				(width 0.1)
				(type default)
			)
			(layer "F.Fab")
		)
		(fp_line
			(start -0.12065 -0.2794)
			(end 0.12065 -0.2794)
			(stroke
				(width 0.1)
				(type default)
			)
			(layer "F.Fab")
		)
		(fp_line
			(start -0.12065 -0.305054)
			(end -0.12065 -0.2794)
			(stroke
				(width 0.1)
				(type default)
			)
			(layer "F.Fab")
		)
		(fp_line
			(start -0.67945 0.3048)
			(end -0.67945 -0.305054)
			(stroke
				(width 0.1)
				(type default)
			)
			(layer "F.Fab")
		)
		(fp_line
			(start -0.67945 -0.305054)
			(end -0.12065 -0.305054)
			(stroke
				(width 0.1)
				(type default)
			)
			(layer "F.Fab")
		)
		(pad "1" smd circle
			(at -0.40005 0 180)
			(size 0 0)
			(layers "F.Cu" "F.Mask" "F.Paste")
			(net "E1S_0_PERST1_CLKREQ_N")
		)
		(pad "2" smd circle
			(at 0.40005 0 180)
			(size 0 0)
			(layers "F.Cu" "F.Mask" "F.Paste")
			(net "GND")
		)
	)
	(footprint ""
		(layer "F.Cu")
		(at 147.53844 -38.95344)
		(property "Reference" "U235"
			(at -1.44272 2.425192 0)
			(unlocked yes)
			(layer "F.SilkS")
			(effects
				(font
					(size 0.7874 0.5842)
					(thickness 0.1524)
				)
				(justify left)
			)
		)
		(property "Value" ""
			(at 0 0 0)
			(layer "F.Fab")
			(effects
				(font
					(size 1.27 1.27)
				)
			)
		)
		(duplicate_pad_numbers_are_jumpers no)
		(fp_line
			(start -1.463548 -1.549908)
			(end -0.787908 -1.549908)
			(stroke
				(width 0.1524)
				(type default)
			)
			(layer "F.SilkS")
		)
		(fp_line
			(start -1.463548 1.549908)
			(end -1.463548 -1.549908)
			(stroke
				(width 0.1524)
				(type default)
			)
			(layer "F.SilkS")
		)
		(fp_line
			(start -0.787908 -1.549908)
			(end 0 -0.762)
			(stroke
				(width 0.1524)
				(type default)
			)
			(layer "F.SilkS")
		)
		(fp_line
			(start 0 -0.762)
			(end 0.762 -1.549908)
			(stroke
				(width 0.1524)
				(type default)
			)
			(layer "F.SilkS")
		)
		(fp_line
			(start 0.762 -1.549908)
			(end 1.463548 -1.549908)
			(stroke
				(width 0.1524)
				(type default)
			)
			(layer "F.SilkS")
		)
		(fp_line
			(start 1.463548 -1.549908)
			(end 1.463548 1.549908)
			(stroke
				(width 0.1524)
				(type default)
			)
			(layer "F.SilkS")
		)
		(fp_line
			(start 1.463548 1.549908)
			(end -1.463548 1.549908)
			(stroke
				(width 0.1524)
				(type default)
			)
			(layer "F.SilkS")
		)
		(fp_poly
			(pts
				(xy -3.062732 -1.753616) (xy -2.624582 -2.191766) (xy -2.40538 -1.534414)
			)
			(stroke
				(width 0)
				(type default)
			)
			(fill yes)
			(layer "F.SilkS")
		)
		(fp_line
			(start -1.549908 -1.549908)
			(end 1.549908 -1.549908)
			(stroke
				(width 0.1)
				(type default)
			)
			(layer "F.Fab")
		)
		(fp_line
			(start -1.549908 1.549908)
			(end -1.549908 -1.549908)
			(stroke
				(width 0.1)
				(type default)
			)
			(layer "F.Fab")
		)
		(fp_line
			(start 1.549908 -1.549908)
			(end 1.549908 1.549908)
			(stroke
				(width 0.1)
				(type default)
			)
			(layer "F.Fab")
		)
		(fp_line
			(start 1.549908 1.549908)
			(end -1.549908 1.549908)
			(stroke
				(width 0.1)
				(type default)
			)
			(layer "F.Fab")
		)
		(fp_poly
			(pts
				(xy -3.4798 -1.359916) (xy -2.86004 -1.050036) (xy -3.4798 -0.740156)
			)
			(stroke
				(width 0)
				(type default)
			)
			(fill yes)
			(layer "F.Fab")
		)
		(pad "1" smd rect
			(at -2.175002 -1.050036 90)
			(size 0.6096 1.1684)
			(layers "F.Cu" "F.Mask" "F.Paste")
			(net "P3V3_AUX")
		)
		(pad "2" smd rect
			(at -2.175002 -0.32512 90)
			(size 0.4318 1.1684)
			(layers "F.Cu" "F.Mask" "F.Paste")
			(net "SMB_OCP_V3_2_3V3AUX_SCL")
		)
		(pad "3" smd rect
			(at -2.175002 0.32512 90)
			(size 0.4318 1.1684)
			(layers "F.Cu" "F.Mask" "F.Paste")
			(net "SMB_OCP_V3_2_3V3AUX_SDA")
		)
		(pad "4" smd rect
			(at -2.175002 1.050036 90)
			(size 0.6096 1.1684)
			(layers "F.Cu" "F.Mask" "F.Paste")
			(net "GND")
		)
		(pad "5" smd rect
			(at 2.175002 1.050036 90)
			(size 0.6096 1.1684)
			(layers "F.Cu" "F.Mask" "F.Paste")
			(net "HP_LVC3_OCP_V3_2_R_EN")
		)
		(pad "6" smd rect
			(at 2.175002 0.32512 90)
			(size 0.4318 1.1684)
			(layers "F.Cu" "F.Mask" "F.Paste")
			(net "SMB_OCP_V3_2_3V3AUX_BUF_SDA")
		)
		(pad "7" smd rect
			(at 2.175002 -0.32512 90)
			(size 0.4318 1.1684)
			(layers "F.Cu" "F.Mask" "F.Paste")
			(net "SMB_OCP_V3_2_3V3AUX_BUF_SCL")
		)
		(pad "8" smd rect
			(at 2.175002 -1.050036 90)
			(size 0.6096 1.1684)
			(layers "F.Cu" "F.Mask" "F.Paste")
			(net "P3V3_OCP_V3_2")
		)
	)
	(footprint ""
		(layer "F.Cu")
		(at 299.543724 -396.412974 90)
		(property "Reference" "R624"
			(at 0 0 90)
			(layer "F.SilkS")
			(hide yes)
			(effects
				(font
					(size 1.27 1.27)
				)
			)
		)
		(property "Value" ""
			(at 0 0 90)
			(layer "F.Fab")
			(effects
				(font
					(size 1.27 1.27)
				)
			)
		)
		(duplicate_pad_numbers_are_jumpers no)
		(fp_line
			(start 0.32512 -0.175006)
			(end 0.32512 0.175006)
			(stroke
				(width 0.1)
				(type default)
			)
			(layer "F.Fab")
		)
		(fp_line
			(start -0.32512 -0.175006)
			(end 0.32512 -0.175006)
			(stroke
				(width 0.1)
				(type default)
			)
			(layer "F.Fab")
		)
		(fp_line
			(start 0.32512 0.175006)
			(end -0.32512 0.175006)
			(stroke
				(width 0.1)
				(type default)
			)
			(layer "F.Fab")
		)
		(fp_line
			(start -0.32512 0.175006)
			(end -0.32512 -0.175006)
			(stroke
				(width 0.1)
				(type default)
			)
			(layer "F.Fab")
		)
		(pad "1" smd rect
			(at -0.2667 0 90)
			(size 0.3048 0.381)
			(layers "F.Cu" "F.Mask" "F.Paste")
			(net "CLK_100M_RETIMER_CPU0_P0_DP")
		)
		(pad "2" smd rect
			(at 0.2667 0 270)
			(size 0.3048 0.381)
			(layers "F.Cu" "F.Mask" "F.Paste")
			(net "GND")
		)
	)
	(footprint ""
		(layer "F.Cu")
		(at 140.420344 -38.796468)
		(property "Reference" "R6209"
			(at 0 0 0)
			(layer "F.SilkS")
			(hide yes)
			(effects
				(font
					(size 1.27 1.27)
				)
			)
		)
		(property "Value" ""
			(at 0 0 0)
			(layer "F.Fab")
			(effects
				(font
					(size 1.27 1.27)
				)
			)
		)
		(duplicate_pad_numbers_are_jumpers no)
		(fp_line
			(start -0.7874 -0.4064)
			(end 0.7874 -0.4064)
			(stroke
				(width 0.1524)
				(type default)
			)
			(layer "F.SilkS")
		)
		(fp_line
			(start -0.7874 0.4064)
			(end -0.7874 -0.4064)
			(stroke
				(width 0.1524)
				(type default)
			)
			(layer "F.SilkS")
		)
		(fp_line
			(start 0.7874 -0.4064)
			(end 0.7874 0.4064)
			(stroke
				(width 0.1524)
				(type default)
			)
			(layer "F.SilkS")
		)
		(fp_line
			(start 0.7874 0.4064)
			(end -0.7874 0.4064)
			(stroke
				(width 0.1524)
				(type default)
			)
			(layer "F.SilkS")
		)
		(fp_line
			(start -0.67945 -0.305054)
			(end -0.12065 -0.305054)
			(stroke
				(width 0.1)
				(type default)
			)
			(layer "F.Fab")
		)
		(fp_line
			(start -0.67945 0.3048)
			(end -0.67945 -0.305054)
			(stroke
				(width 0.1)
				(type default)
			)
			(layer "F.Fab")
		)
		(fp_line
			(start -0.12065 -0.305054)
			(end -0.12065 -0.2794)
			(stroke
				(width 0.1)
				(type default)
			)
			(layer "F.Fab")
		)
		(fp_line
			(start -0.12065 -0.2794)
			(end 0.12065 -0.2794)
			(stroke
				(width 0.1)
				(type default)
			)
			(layer "F.Fab")
		)
		(fp_line
			(start -0.12065 0.2794)
			(end -0.12065 0.3048)
			(stroke
				(width 0.1)
				(type default)
			)
			(layer "F.Fab")
		)
		(fp_line
			(start -0.12065 0.3048)
			(end -0.67945 0.3048)
			(stroke
				(width 0.1)
				(type default)
			)
			(layer "F.Fab")
		)
		(fp_line
			(start 0.120396 0.2794)
			(end -0.12065 0.2794)
			(stroke
				(width 0.1)
				(type default)
			)
			(layer "F.Fab")
		)
		(fp_line
			(start 0.120396 0.3048)
			(end 0.120396 0.2794)
			(stroke
				(width 0.1)
				(type default)
			)
			(layer "F.Fab")
		)
		(fp_line
			(start 0.12065 -0.3048)
			(end 0.67945 -0.3048)
			(stroke
				(width 0.1)
				(type default)
			)
			(layer "F.Fab")
		)
		(fp_line
			(start 0.12065 -0.2794)
			(end 0.12065 -0.3048)
			(stroke
				(width 0.1)
				(type default)
			)
			(layer "F.Fab")
		)
		(fp_line
			(start 0.67945 -0.3048)
			(end 0.67945 0.3048)
			(stroke
				(width 0.1)
				(type default)
			)
			(layer "F.Fab")
		)
		(fp_line
			(start 0.67945 0.3048)
			(end 0.120396 0.3048)
			(stroke
				(width 0.1)
				(type default)
			)
			(layer "F.Fab")
		)
		(pad "1" smd circle
			(at -0.40005 0)
			(size 0 0)
			(layers "F.Cu" "F.Mask" "F.Paste")
			(net "USB_CPU0_HUB1_VBUS_US")
		)
		(pad "2" smd circle
			(at 0.40005 0)
			(size 0 0)
			(layers "F.Cu" "F.Mask" "F.Paste")
			(net "GND")
		)
	)
)
